(kicad_pcb
	(version 20260206)
	(generator "pcbnew")
	(generator_version "10.0")
	(general
		(thickness 1.6)
		(legacy_teardrops no)
	)
	(paper "A4")
	(title_block
		(title "12092022_DA0F0TFB6D0_F0T_FAN_BOARD_MP5048_D_brd_v02_OCP.brd")
		(comment 1 "Grand Teton / footprints 286-290 of 924")
	)
	(layers
		(0 "F.Cu" signal "TOP")
		(4 "In1.Cu" signal "GND")
		(6 "In2.Cu" signal "IN1")
		(8 "In3.Cu" signal "IN2")
		(10 "In4.Cu" signal "GND1")
		(2 "B.Cu" signal "BOTTOM")
		(9 "F.Adhes" user "F.Adhesive")
		(11 "B.Adhes" user "B.Adhesive")
		(13 "F.Paste" user "Package Geometry/Pastemask Top")
		(15 "B.Paste" user "Package Geometry/Pastemask Bottom")
		(5 "F.SilkS" user "Ref Des/Silkscreen Top")
		(7 "B.SilkS" user "Ref Des/Silkscreen Bottom")
		(1 "F.Mask" user "Board Geometry/Soldermask Top")
		(3 "B.Mask" user "Board Geometry/Soldermask Bottom")
		(17 "Dwgs.User" user "User.Drawings")
		(19 "Cmts.User" user "User.Comments")
		(21 "Eco1.User" user "User.Eco1")
		(23 "Eco2.User" user "User.Eco2")
		(25 "Edge.Cuts" user "Board Geometry/Outline")
		(27 "Margin" user)
		(31 "F.CrtYd" user "Package Geometry/Place Bound Top")
		(29 "B.CrtYd" user "Package Geometry/Place Bound Bottom")
		(35 "F.Fab" user "Ref Des/Assembly Top")
		(33 "B.Fab" user "Ref Des/Assembly Bottom")
	)
	(footprint ""
		(layer "F.Cu")
		(at 36.195 -16.256)
		(property "Reference" "D143"
			(at 2.286 -0.86233 0)
			(unlocked yes)
			(layer "F.SilkS")
			(effects
				(font
					(size 0.7874 0.5842)
					(thickness 0.1524)
				)
				(justify left)
			)
		)
		(property "Value" ""
			(at 0 0 0)
			(layer "F.Fab")
			(effects
				(font
					(size 1.27 1.27)
				)
			)
		)
		(duplicate_pad_numbers_are_jumpers no)
		(fp_line
			(start -1.651 -0.7112)
			(end 2.032 -0.7112)
			(stroke
				(width 0.1524)
				(type default)
			)
			(layer "F.SilkS")
		)
		(fp_line
			(start -1.651 0.7112)
			(end -1.651 -0.7112)
			(stroke
				(width 0.1524)
				(type default)
			)
			(layer "F.SilkS")
		)
		(fp_line
			(start -0.299974 -0.500126)
			(end -0.299974 0.500126)
			(stroke
				(width 0.1524)
				(type default)
			)
			(layer "F.SilkS")
		)
		(fp_line
			(start -0.299974 0.500126)
			(end 0.199898 0)
			(stroke
				(width 0.1524)
				(type default)
			)
			(layer "F.SilkS")
		)
		(fp_line
			(start 0.199898 0)
			(end -0.299974 -0.500126)
			(stroke
				(width 0.1524)
				(type default)
			)
			(layer "F.SilkS")
		)
		(fp_line
			(start 0.299974 -0.500126)
			(end 0.299974 0.500126)
			(stroke
				(width 0.1524)
				(type default)
			)
			(layer "F.SilkS")
		)
		(fp_line
			(start 1.651 -0.6858)
			(end 1.651 0.6858)
			(stroke
				(width 0.1524)
				(type default)
			)
			(layer "F.SilkS")
		)
		(fp_line
			(start 1.778 0.6858)
			(end 1.778 -0.6858)
			(stroke
				(width 0.1524)
				(type default)
			)
			(layer "F.SilkS")
		)
		(fp_line
			(start 1.905 -0.6858)
			(end 1.905 0.6858)
			(stroke
				(width 0.1524)
				(type default)
			)
			(layer "F.SilkS")
		)
		(fp_line
			(start 2.032 -0.7112)
			(end 2.032 0.7112)
			(stroke
				(width 0.1524)
				(type default)
			)
			(layer "F.SilkS")
		)
		(fp_line
			(start 2.032 0.7112)
			(end -1.651 0.7112)
			(stroke
				(width 0.1524)
				(type default)
			)
			(layer "F.SilkS")
		)
		(fp_line
			(start -1.35001 -0.225044)
			(end -0.899922 -0.225044)
			(stroke
				(width 0.1)
				(type default)
			)
			(layer "F.Fab")
		)
		(fp_line
			(start -1.35001 0.175006)
			(end -1.35001 -0.225044)
			(stroke
				(width 0.1)
				(type default)
			)
			(layer "F.Fab")
		)
		(fp_line
			(start -0.899922 -0.700024)
			(end 0.899922 -0.700024)
			(stroke
				(width 0.1)
				(type default)
			)
			(layer "F.Fab")
		)
		(fp_line
			(start -0.899922 -0.225044)
			(end -0.899922 -0.700024)
			(stroke
				(width 0.1)
				(type default)
			)
			(layer "F.Fab")
		)
		(fp_line
			(start -0.899922 0.175006)
			(end -1.35001 0.175006)
			(stroke
				(width 0.1)
				(type default)
			)
			(layer "F.Fab")
		)
		(fp_line
			(start -0.899922 0.700024)
			(end -0.899922 0.175006)
			(stroke
				(width 0.1)
				(type default)
			)
			(layer "F.Fab")
		)
		(fp_line
			(start -0.299974 -0.500126)
			(end -0.299974 0.500126)
			(stroke
				(width 0.1)
				(type default)
			)
			(layer "F.Fab")
		)
		(fp_line
			(start -0.299974 0.500126)
			(end 0.199898 0)
			(stroke
				(width 0.1)
				(type default)
			)
			(layer "F.Fab")
		)
		(fp_line
			(start 0.199898 0)
			(end -0.299974 -0.500126)
			(stroke
				(width 0.1)
				(type default)
			)
			(layer "F.Fab")
		)
		(fp_line
			(start 0.299974 -0.500126)
			(end 0.299974 0.500126)
			(stroke
				(width 0.1)
				(type default)
			)
			(layer "F.Fab")
		)
		(fp_line
			(start 0.899922 -0.700024)
			(end 0.899922 -0.225044)
			(stroke
				(width 0.1)
				(type default)
			)
			(layer "F.Fab")
		)
		(fp_line
			(start 0.899922 -0.225044)
			(end 1.35001 -0.225044)
			(stroke
				(width 0.1)
				(type default)
			)
			(layer "F.Fab")
		)
		(fp_line
			(start 0.899922 0.175006)
			(end 0.899922 0.700024)
			(stroke
				(width 0.1)
				(type default)
			)
			(layer "F.Fab")
		)
		(fp_line
			(start 0.899922 0.700024)
			(end -0.899922 0.700024)
			(stroke
				(width 0.1)
				(type default)
			)
			(layer "F.Fab")
		)
		(fp_line
			(start 1.35001 -0.225044)
			(end 1.35001 0.175006)
			(stroke
				(width 0.1)
				(type default)
			)
			(layer "F.Fab")
		)
		(fp_line
			(start 1.35001 0.175006)
			(end 0.899922 0.175006)
			(stroke
				(width 0.1)
				(type default)
			)
			(layer "F.Fab")
		)
		(fp_text user "+"
			(at -1.37795 0.381 270)
			(unlocked yes)
			(layer "F.SilkS")
			(effects
				(font
					(size 1.905 1.4224)
					(thickness 0.1524)
				)
				(justify left)
			)
		)
		(fp_text user "-"
			(at 1.905 -0.22225 0)
			(unlocked yes)
			(layer "F.SilkS")
			(effects
				(font
					(size 1.905 1.4224)
					(thickness 0.1524)
				)
				(justify left)
			)
		)
		(fp_text user "+"
			(at -2.794 -0.19685 0)
			(unlocked yes)
			(layer "F.Fab")
			(effects
				(font
					(size 1.905 1.4224)
					(thickness 0.1524)
				)
				(justify left)
			)
		)
		(fp_text user "-"
			(at 1.8288 -0.24765 0)
			(unlocked yes)
			(layer "F.Fab")
			(effects
				(font
					(size 1.905 1.4224)
					(thickness 0.1524)
				)
				(justify left)
			)
		)
		(pad "1" smd rect
			(at -1.0922 0 180)
			(size 0.8128 0.8636)
			(layers "F.Cu" "F.Mask" "F.Paste")
			(net "FAN_3_TACH_OL_R")
		)
		(pad "2" smd rect
			(at 1.0922 0)
			(size 0.8128 0.8636)
			(layers "F.Cu" "F.Mask" "F.Paste")
			(net "FAN_3_TACH_OL_D")
		)
	)
	(footprint ""
		(layer "F.Cu")
		(at 5.842 -135.255 -90)
		(property "Reference" "R5569"
			(at 0 0 270)
			(layer "F.SilkS")
			(hide yes)
			(effects
				(font
					(size 1.27 1.27)
				)
			)
		)
		(property "Value" ""
			(at 0 0 270)
			(layer "F.Fab")
			(effects
				(font
					(size 1.27 1.27)
				)
			)
		)
		(duplicate_pad_numbers_are_jumpers no)
		(fp_line
			(start -0.7874 0.4064)
			(end -0.7874 -0.4064)
			(stroke
				(width 0.1524)
				(type default)
			)
			(layer "F.SilkS")
		)
		(fp_line
			(start 0.7874 0.4064)
			(end -0.7874 0.4064)
			(stroke
				(width 0.1524)
				(type default)
			)
			(layer "F.SilkS")
		)
		(fp_line
			(start -0.7874 -0.4064)
			(end 0.7874 -0.4064)
			(stroke
				(width 0.1524)
				(type default)
			)
			(layer "F.SilkS")
		)
		(fp_line
			(start 0.7874 -0.4064)
			(end 0.7874 0.4064)
			(stroke
				(width 0.1524)
				(type default)
			)
			(layer "F.SilkS")
		)
		(fp_line
			(start -0.67945 0.3048)
			(end -0.67945 -0.305054)
			(stroke
				(width 0.1)
				(type default)
			)
			(layer "F.Fab")
		)
		(fp_line
			(start -0.12065 0.3048)
			(end -0.67945 0.3048)
			(stroke
				(width 0.1)
				(type default)
			)
			(layer "F.Fab")
		)
		(fp_line
			(start 0.120396 0.3048)
			(end 0.120396 0.2794)
			(stroke
				(width 0.1)
				(type default)
			)
			(layer "F.Fab")
		)
		(fp_line
			(start 0.67945 0.3048)
			(end 0.120396 0.3048)
			(stroke
				(width 0.1)
				(type default)
			)
			(layer "F.Fab")
		)
		(fp_line
			(start -0.12065 0.2794)
			(end -0.12065 0.3048)
			(stroke
				(width 0.1)
				(type default)
			)
			(layer "F.Fab")
		)
		(fp_line
			(start 0.120396 0.2794)
			(end -0.12065 0.2794)
			(stroke
				(width 0.1)
				(type default)
			)
			(layer "F.Fab")
		)
		(fp_line
			(start -0.12065 -0.2794)
			(end 0.12065 -0.2794)
			(stroke
				(width 0.1)
				(type default)
			)
			(layer "F.Fab")
		)
		(fp_line
			(start 0.12065 -0.2794)
			(end 0.12065 -0.3048)
			(stroke
				(width 0.1)
				(type default)
			)
			(layer "F.Fab")
		)
		(fp_line
			(start 0.12065 -0.3048)
			(end 0.67945 -0.3048)
			(stroke
				(width 0.1)
				(type default)
			)
			(layer "F.Fab")
		)
		(fp_line
			(start 0.67945 -0.3048)
			(end 0.67945 0.3048)
			(stroke
				(width 0.1)
				(type default)
			)
			(layer "F.Fab")
		)
		(fp_line
			(start -0.67945 -0.305054)
			(end -0.12065 -0.305054)
			(stroke
				(width 0.1)
				(type default)
			)
			(layer "F.Fab")
		)
		(fp_line
			(start -0.12065 -0.305054)
			(end -0.12065 -0.2794)
			(stroke
				(width 0.1)
				(type default)
			)
			(layer "F.Fab")
		)
		(pad "1" smd circle
			(at -0.40005 0 270)
			(size 0 0)
			(layers "F.Cu" "F.Mask" "F.Paste")
			(net "SMB_PDBV_FAN_SCL")
		)
		(pad "2" smd circle
			(at 0.40005 0 270)
			(size 0 0)
			(layers "F.Cu" "F.Mask" "F.Paste")
			(net "SMB_PDBV_FAN_R_U404_SCL")
		)
	)
	(footprint ""
		(layer "F.Cu")
		(at 42.037 -181.102)
		(property "Reference" "R518"
			(at 0 0 0)
			(layer "F.SilkS")
			(hide yes)
			(effects
				(font
					(size 1.27 1.27)
				)
			)
		)
		(property "Value" ""
			(at 0 0 0)
			(layer "F.Fab")
			(effects
				(font
					(size 1.27 1.27)
				)
			)
		)
		(duplicate_pad_numbers_are_jumpers no)
		(fp_line
			(start -0.7874 -0.4064)
			(end 0.7874 -0.4064)
			(stroke
				(width 0.1524)
				(type default)
			)
			(layer "F.SilkS")
		)
		(fp_line
			(start -0.7874 0.4064)
			(end -0.7874 -0.4064)
			(stroke
				(width 0.1524)
				(type default)
			)
			(layer "F.SilkS")
		)
		(fp_line
			(start 0.7874 -0.4064)
			(end 0.7874 0.4064)
			(stroke
				(width 0.1524)
				(type default)
			)
			(layer "F.SilkS")
		)
		(fp_line
			(start 0.7874 0.4064)
			(end -0.7874 0.4064)
			(stroke
				(width 0.1524)
				(type default)
			)
			(layer "F.SilkS")
		)
		(fp_line
			(start -0.67945 -0.305054)
			(end -0.12065 -0.305054)
			(stroke
				(width 0.1)
				(type default)
			)
			(layer "F.Fab")
		)
		(fp_line
			(start -0.67945 0.3048)
			(end -0.67945 -0.305054)
			(stroke
				(width 0.1)
				(type default)
			)
			(layer "F.Fab")
		)
		(fp_line
			(start -0.12065 -0.305054)
			(end -0.12065 -0.2794)
			(stroke
				(width 0.1)
				(type default)
			)
			(layer "F.Fab")
		)
		(fp_line
			(start -0.12065 -0.2794)
			(end 0.12065 -0.2794)
			(stroke
				(width 0.1)
				(type default)
			)
			(layer "F.Fab")
		)
		(fp_line
			(start -0.12065 0.2794)
			(end -0.12065 0.3048)
			(stroke
				(width 0.1)
				(type default)
			)
			(layer "F.Fab")
		)
		(fp_line
			(start -0.12065 0.3048)
			(end -0.67945 0.3048)
			(stroke
				(width 0.1)
				(type default)
			)
			(layer "F.Fab")
		)
		(fp_line
			(start 0.120396 0.2794)
			(end -0.12065 0.2794)
			(stroke
				(width 0.1)
				(type default)
			)
			(layer "F.Fab")
		)
		(fp_line
			(start 0.120396 0.3048)
			(end 0.120396 0.2794)
			(stroke
				(width 0.1)
				(type default)
			)
			(layer "F.Fab")
		)
		(fp_line
			(start 0.12065 -0.3048)
			(end 0.67945 -0.3048)
			(stroke
				(width 0.1)
				(type default)
			)
			(layer "F.Fab")
		)
		(fp_line
			(start 0.12065 -0.2794)
			(end 0.12065 -0.3048)
			(stroke
				(width 0.1)
				(type default)
			)
			(layer "F.Fab")
		)
		(fp_line
			(start 0.67945 -0.3048)
			(end 0.67945 0.3048)
			(stroke
				(width 0.1)
				(type default)
			)
			(layer "F.Fab")
		)
		(fp_line
			(start 0.67945 0.3048)
			(end 0.120396 0.3048)
			(stroke
				(width 0.1)
				(type default)
			)
			(layer "F.Fab")
		)
		(pad "1" smd circle
			(at -0.40005 0)
			(size 0 0)
			(layers "F.Cu" "F.Mask" "F.Paste")
			(net "PD_FAN_BUFF_INPUT_U336E")
		)
		(pad "2" smd circle
			(at 0.40005 0)
			(size 0 0)
			(layers "F.Cu" "F.Mask" "F.Paste")
			(net "P3V3_AUX")
		)
	)
	(footprint ""
		(layer "F.Cu")
		(at 18.679922 -101.950012 180)
		(property "Reference" "D249"
			(at 1.407922 -1.646682 0)
			(unlocked yes)
			(layer "F.SilkS")
			(effects
				(font
					(size 0.7874 0.5842)
					(thickness 0.1524)
				)
				(justify left)
			)
		)
		(property "Value" ""
			(at 0 0 180)
			(layer "F.Fab")
			(effects
				(font
					(size 1.27 1.27)
				)
			)
		)
		(duplicate_pad_numbers_are_jumpers no)
		(fp_line
			(start 0.94488 0.450088)
			(end 0.94488 -0.450088)
			(stroke
				(width 0.1524)
				(type default)
			)
			(layer "F.SilkS")
		)
		(fp_line
			(start 0.94488 -0.450088)
			(end -0.854964 -0.450088)
			(stroke
				(width 0.1524)
				(type default)
			)
			(layer "F.SilkS")
		)
		(fp_line
			(start 0.870458 -0.2794)
			(end 0.845058 0.4064)
			(stroke
				(width 0.1524)
				(type default)
			)
			(layer "F.SilkS")
		)
		(fp_line
			(start 0.845058 0.4064)
			(end 0.845058 -0.381)
			(stroke
				(width 0.1524)
				(type default)
			)
			(layer "F.SilkS")
		)
		(fp_line
			(start -0.854964 0.450088)
			(end 0.925068 0.450088)
			(stroke
				(width 0.1524)
				(type default)
			)
			(layer "F.SilkS")
		)
		(fp_line
			(start -0.854964 -0.450088)
			(end -0.854964 0.450088)
			(stroke
				(width 0.1524)
				(type default)
			)
			(layer "F.SilkS")
		)
		(fp_line
			(start 0.54991 0.350012)
			(end 0.54991 -0.350012)
			(stroke
				(width 0.1)
				(type default)
			)
			(layer "F.Fab")
		)
		(fp_line
			(start 0.54991 -0.350012)
			(end -0.54991 -0.350012)
			(stroke
				(width 0.1)
				(type default)
			)
			(layer "F.Fab")
		)
		(fp_line
			(start -0.54991 0.350012)
			(end 0.54991 0.350012)
			(stroke
				(width 0.1)
				(type default)
			)
			(layer "F.Fab")
		)
		(fp_line
			(start -0.54991 -0.350012)
			(end -0.54991 0.350012)
			(stroke
				(width 0.1)
				(type default)
			)
			(layer "F.Fab")
		)
		(fp_text user "-"
			(at 1.915922 -0.635762 0)
			(unlocked yes)
			(layer "F.SilkS")
			(effects
				(font
					(size 1.905 1.4224)
					(thickness 0.1524)
				)
				(justify left)
			)
		)
		(fp_text user "+"
			(at -0.751078 0.761238 0)
			(unlocked yes)
			(layer "F.SilkS")
			(effects
				(font
					(size 1.905 1.4224)
					(thickness 0.1524)
				)
				(justify left)
			)
		)
		(fp_text user "-"
			(at 2.48539 0.239014 0)
			(unlocked yes)
			(layer "F.Fab")
			(effects
				(font
					(size 1.905 1.4224)
					(thickness 0.1524)
				)
				(justify left)
			)
		)
		(fp_text user "+"
			(at -0.808228 0.239014 0)
			(unlocked yes)
			(layer "F.Fab")
			(effects
				(font
					(size 1.905 1.4224)
					(thickness 0.1524)
				)
				(justify left)
			)
		)
		(pad "A" smd rect
			(at -0.424942 0 180)
			(size 0.5588 0.6096)
			(layers "F.Cu" "F.Mask" "F.Paste")
			(net "GND")
		)
		(pad "C" smd rect
			(at 0.424942 0)
			(size 0.5588 0.6096)
			(layers "F.Cu" "F.Mask" "F.Paste")
			(net "FAN_5_PWM_OL_R")
		)
	)
	(footprint ""
		(layer "F.Cu")
		(at 9.144 -184.785 180)
		(property "Reference" "R5486"
			(at 0 0 180)
			(layer "F.SilkS")
			(hide yes)
			(effects
				(font
					(size 1.27 1.27)
				)
			)
		)
		(property "Value" ""
			(at 0 0 180)
			(layer "F.Fab")
			(effects
				(font
					(size 1.27 1.27)
				)
			)
		)
		(duplicate_pad_numbers_are_jumpers no)
		(fp_line
			(start 0.7874 0.4064)
			(end -0.7874 0.4064)
			(stroke
				(width 0.1524)
				(type default)
			)
			(layer "F.SilkS")
		)
		(fp_line
			(start 0.7874 -0.4064)
			(end 0.7874 0.4064)
			(stroke
				(width 0.1524)
				(type default)
			)
			(layer "F.SilkS")
		)
		(fp_line
			(start -0.7874 0.4064)
			(end -0.7874 -0.4064)
			(stroke
				(width 0.1524)
				(type default)
			)
			(layer "F.SilkS")
		)
		(fp_line
			(start -0.7874 -0.4064)
			(end 0.7874 -0.4064)
			(stroke
				(width 0.1524)
				(type default)
			)
			(layer "F.SilkS")
		)
		(fp_line
			(start 0.67945 0.3048)
			(end 0.120396 0.3048)
			(stroke
				(width 0.1)
				(type default)
			)
			(layer "F.Fab")
		)
		(fp_line
			(start 0.67945 -0.3048)
			(end 0.67945 0.3048)
			(stroke
				(width 0.1)
				(type default)
			)
			(layer "F.Fab")
		)
		(fp_line
			(start 0.12065 -0.2794)
			(end 0.12065 -0.3048)
			(stroke
				(width 0.1)
				(type default)
			)
			(layer "F.Fab")
		)
		(fp_line
			(start 0.12065 -0.3048)
			(end 0.67945 -0.3048)
			(stroke
				(width 0.1)
				(type default)
			)
			(layer "F.Fab")
		)
		(fp_line
			(start 0.120396 0.3048)
			(end 0.120396 0.2794)
			(stroke
				(width 0.1)
				(type default)
			)
			(layer "F.Fab")
		)
		(fp_line
			(start 0.120396 0.2794)
			(end -0.12065 0.2794)
			(stroke
				(width 0.1)
				(type default)
			)
			(layer "F.Fab")
		)
		(fp_line
			(start -0.12065 0.3048)
			(end -0.67945 0.3048)
			(stroke
				(width 0.1)
				(type default)
			)
			(layer "F.Fab")
		)
		(fp_line
			(start -0.12065 0.2794)
			(end -0.12065 0.3048)
			(stroke
				(width 0.1)
				(type default)
			)
			(layer "F.Fab")
		)
		(fp_line
			(start -0.12065 -0.2794)
			(end 0.12065 -0.2794)
			(stroke
				(width 0.1)
				(type default)
			)
			(layer "F.Fab")
		)
		(fp_line
			(start -0.12065 -0.305054)
			(end -0.12065 -0.2794)
			(stroke
				(width 0.1)
				(type default)
			)
			(layer "F.Fab")
		)
		(fp_line
			(start -0.67945 0.3048)
			(end -0.67945 -0.305054)
			(stroke
				(width 0.1)
				(type default)
			)
			(layer "F.Fab")
		)
		(fp_line
			(start -0.67945 -0.305054)
			(end -0.12065 -0.305054)
			(stroke
				(width 0.1)
				(type default)
			)
			(layer "F.Fab")
		)
		(pad "1" smd circle
			(at -0.40005 0 180)
			(size 0 0)
			(layers "F.Cu" "F.Mask" "F.Paste")
			(net "P3V3_AUX")
		)
		(pad "2" smd circle
			(at 0.40005 0 180)
			(size 0 0)
			(layers "F.Cu" "F.Mask" "F.Paste")
			(net "PU_U7_PIN2")
		)
	)
)
